%FSTAX23Y23*%
%MOIN*%
%SFA1B1*%

%IPPOS*%
%ADD59R,0.165350X0.125980*%
%ADD79R,0.314960X0.135830*%
%ADD80R,1.354330X0.230320*%
%ADD81O,0.086740X0.031620*%
%ADD82R,0.047370X0.082800*%
%ADD83R,0.078870X0.082800*%
%ADD84R,0.063910X0.069020*%
%ADD85R,0.025720X0.062330*%
%ADD86R,0.072960X0.059180*%
%ADD87R,0.086740X0.106420*%
%ADD88R,0.027690X0.098550*%
%ADD89R,0.049340X0.047370*%
%ADD90R,0.094610X0.049340*%
%ADD91R,0.027690X0.043430*%
%ADD92O,0.065090X0.025720*%
%ADD93R,0.085560X0.030440*%
%ADD94R,0.033590X0.049340*%
%ADD95R,0.059180X0.082800*%
%ADD96R,0.047370X0.078870*%
%ADD97R,0.047370X0.098550*%
%ADD98R,0.049340X0.053280*%
%ADD99R,0.035560X0.053280*%
%ADD100R,0.061150X0.035560*%
%ADD101R,0.058000X0.208000*%
%ADD102R,0.065090X0.045400*%
%ADD103R,0.036350X0.047370*%
%ADD104R,0.033590X0.031620*%
%ADD105R,0.036000X0.173000*%
%ADD106R,0.036000X0.134000*%
%ADD107R,0.039500X0.074930*%
%ADD108R,0.078870X0.017840*%
%ADD109R,0.034580X0.017840*%
%ADD110R,0.017840X0.030640*%
%ADD111R,0.035560X0.043430*%
%ADD112R,0.046580X0.042250*%
%ADD113R,0.220600X0.122170*%
%ADD114R,0.104460X0.132020*%
%ADD115R,0.041470X0.047370*%
%ADD116R,0.065090X0.053280*%
%ADD117R,0.045400X0.047370*%
%ADD118R,0.033200X0.034770*%
%ADD119R,0.018830X0.017840*%
%ADD120R,0.017840X0.018830*%
%ADD121R,0.069020X0.017840*%
%ADD122R,0.074930X0.061150*%
%ADD123R,0.017840X0.069020*%
%ADD124R,0.061150X0.074930*%
%ADD125R,0.053280X0.065090*%
%ADD126R,0.034770X0.033200*%
%ADD127R,0.047370X0.045400*%
%ADD128R,0.047370X0.041470*%
%ADD129R,0.047370X0.036350*%
%ADD130R,0.031620X0.033590*%
%ADD131R,0.090870X0.052090*%
%ADD132R,0.043430X0.035560*%
%ADD133C,0.039500*%
%ADD134C,0.073980*%
%ADD135C,0.008000*%
%ADD136C,0.069020*%
%ADD137R,0.069020X0.069020*%
%ADD138C,0.083000*%
%ADD139C,0.106420*%
%ADD140O,0.096580X0.185170*%
%ADD141O,0.185170X0.096580*%
%ADD142O,0.204850X0.106420*%
%ADD143C,0.120000*%
%ADD144C,0.128000*%
%ADD145R,0.008000X0.008000*%
%ADD146C,0.029660*%
%ADD147C,0.063000*%
%ADD148R,0.063000X0.063000*%
%ADD149C,0.058000*%
%ADD150C,0.258000*%
%ADD151C,0.024000*%
%ADD152C,0.208000*%
%LNgrandmaster-1*%
%LPD*%
G54D59*
X04909Y03961D03*
Y02808D03*
G54D79*
X0147Y00245D03*
G54D80*
X02446Y00111D03*
G54D81*
X02756Y03287D03*
Y03237D03*
Y03187D03*
Y03137D03*
Y03087D03*
Y03037D03*
Y02987D03*
Y02937D03*
X03111Y03287D03*
Y03237D03*
Y03187D03*
Y03137D03*
Y03087D03*
Y03037D03*
Y02987D03*
Y02937D03*
G54D82*
X02271Y04275D03*
G54D83*
X02377Y04275D03*
G54D84*
X02234Y04173D03*
X0243D03*
G54D85*
X02383Y0417D03*
X02358D03*
X02332D03*
X02306D03*
X02281D03*
G54D86*
X02465Y04275D03*
X02199D03*
G54D87*
X04046Y04244D03*
Y04027D03*
X03696D03*
Y04244D03*
G54D88*
X03934Y04023D03*
X03902D03*
X03871D03*
X03839D03*
X03808D03*
G54D89*
X00594Y00906D03*
Y01956D03*
Y02481D03*
Y01431D03*
G54D90*
X00654Y00964D03*
Y00847D03*
Y01897D03*
Y02014D03*
Y02422D03*
Y02539D03*
Y01489D03*
Y01372D03*
G54D91*
X03469Y03661D03*
X03444Y0375D03*
X03495D03*
X02834Y03661D03*
X02809Y0375D03*
X0286D03*
X02719Y03661D03*
X02694Y0375D03*
X02745D03*
X03244Y03661D03*
X03219Y0375D03*
X0327D03*
G54D92*
X01846Y04024D03*
Y04049D03*
Y04074D03*
Y04099D03*
Y04124D03*
Y04149D03*
Y04174D03*
Y04199D03*
X01631Y04024D03*
Y04049D03*
Y04074D03*
Y04099D03*
Y04124D03*
Y04149D03*
Y04174D03*
Y04199D03*
X03987Y03683D03*
Y03708D03*
Y03733D03*
Y03758D03*
Y03783D03*
Y03808D03*
Y03833D03*
Y03858D03*
X03772Y03683D03*
Y03708D03*
Y03733D03*
Y03758D03*
Y03783D03*
Y03808D03*
Y03833D03*
Y03858D03*
G54D93*
X06352Y02241D03*
Y02291D03*
Y02341D03*
Y02391D03*
X06157D03*
Y02341D03*
Y02291D03*
Y02241D03*
X06637Y02031D03*
Y01981D03*
Y01931D03*
Y01881D03*
X06832D03*
Y01931D03*
Y01981D03*
Y02031D03*
G54D94*
X06341Y03701D03*
X06197D03*
X06031D03*
X05887D03*
X06202Y03566D03*
X06346D03*
G54D95*
X06726Y03168D03*
X06943D03*
Y03294D03*
X06726D03*
G54D96*
X03451Y03206D03*
X03392D03*
X03451Y03395D03*
X0351D03*
X03569Y03206D03*
X03333Y03395D03*
Y03206D03*
X0351D03*
X03392Y03395D03*
G54D97*
X03569Y03385D03*
G54D98*
X03438Y03051D03*
Y02892D03*
X03531Y03051D03*
Y02892D03*
G54D99*
X03484Y02892D03*
Y03051D03*
G54D100*
X03444Y02995D03*
Y02948D03*
X03525D03*
Y02995D03*
G54D101*
X03344Y04221D03*
Y03951D03*
X03244Y04221D03*
Y03951D03*
X03144Y04221D03*
Y03951D03*
X03044Y04221D03*
Y03951D03*
X02944Y04221D03*
Y03951D03*
G54D102*
X03349Y03666D03*
Y03745D03*
X02944Y03666D03*
Y03745D03*
X03044Y03666D03*
Y03745D03*
X03144Y03666D03*
Y03745D03*
G54D103*
X03477Y02797D03*
X03532D03*
X06035Y03556D03*
X0609D03*
X0415Y03603D03*
X04204D03*
X06897Y01816D03*
X06842D03*
X06782D03*
X06727D03*
X06367Y02451D03*
X06312D03*
X04167Y03701D03*
X04112D03*
X04652Y04206D03*
X04707D03*
X05212D03*
X05267D03*
X04652Y04121D03*
X04707D03*
X05267Y04126D03*
X05212D03*
G54D104*
X03701Y03786D03*
X03668D03*
X03701Y03861D03*
X03668D03*
G54D105*
X02545Y00137D03*
X02466D03*
X02348D03*
X0282D03*
X01915D03*
X02033D03*
X02663D03*
X02702D03*
X0286D03*
X02978D03*
X0219D03*
X01994D03*
X01954D03*
X03017D03*
X02309D03*
X02112D03*
X02151D03*
X02387D03*
X02427D03*
X02584D03*
X02624D03*
X02742D03*
X02781D03*
X02899D03*
X02938D03*
X02505D03*
X02072D03*
X01797D03*
X01836D03*
X01875D03*
X03096D03*
G54D106*
X03057Y00157D03*
G54D107*
X04957Y04206D03*
X05091D03*
X04432D03*
X04566D03*
G54D108*
X04068Y01599D03*
X03911D03*
Y01619D03*
X04068D03*
X03911Y01639D03*
X04068D03*
X03911Y01659D03*
X04068D03*
X03911Y01679D03*
X04068D03*
X03911Y01699D03*
X04068D03*
X03911Y01719D03*
X04068D03*
X03911Y01739D03*
X04068D03*
X03911Y01759D03*
X04068D03*
X03911Y01779D03*
X04068D03*
G54D109*
X06511Y03191D03*
Y03172D03*
Y03211D03*
Y03231D03*
Y0325D03*
Y0327D03*
Y0329D03*
Y03309D03*
Y03329D03*
X06388D03*
Y03309D03*
Y0329D03*
Y0327D03*
Y0325D03*
Y03231D03*
Y03211D03*
Y03191D03*
Y03172D03*
Y03152D03*
X06511D03*
G54D110*
X06479Y03332D03*
X06459D03*
X0644D03*
X0642D03*
Y0315D03*
X0644D03*
X06459D03*
X06479D03*
G54D111*
X00901Y00718D03*
X0096D03*
X00908Y02284D03*
X00967D03*
X009Y01747D03*
X00959D03*
X00904Y01224D03*
X00963D03*
G54D112*
X04149Y02789D03*
Y02842D03*
X04434Y02789D03*
Y02842D03*
G54D113*
X06679Y0242D03*
Y02802D03*
X06319Y01842D03*
Y0146D03*
G54D114*
X01157Y00906D03*
X00932D03*
Y01956D03*
X01157D03*
X00932Y02481D03*
X01157D03*
Y01431D03*
X00932D03*
G54D115*
X01249Y04254D03*
Y04197D03*
X03589Y03852D03*
Y03909D03*
Y03784D03*
Y03727D03*
X00644Y04197D03*
Y04254D03*
X00846Y04197D03*
Y04254D03*
X01048D03*
Y04197D03*
G54D116*
X04339Y0278D03*
Y02851D03*
X06334Y0211D03*
Y02181D03*
X06659Y02166D03*
Y02095D03*
X06253Y02826D03*
Y02755D03*
X06372Y02826D03*
Y02755D03*
X04104Y0377D03*
Y03841D03*
X02209Y03716D03*
Y03645D03*
X02639Y03535D03*
Y03606D03*
X03693Y03188D03*
Y03117D03*
X04064Y0278D03*
Y02851D03*
X03959Y0278D03*
Y02851D03*
X04234Y0278D03*
Y02851D03*
G54D117*
X04039Y03029D03*
Y03092D03*
X06469Y02239D03*
Y02302D03*
X06519Y01954D03*
Y02017D03*
X04194Y03774D03*
Y03837D03*
X03688Y03266D03*
Y03329D03*
X06604Y03264D03*
Y03327D03*
Y03192D03*
Y03129D03*
G54D118*
X04109Y03044D03*
Y03077D03*
X06939Y01889D03*
Y01922D03*
X06064Y02344D03*
Y02377D03*
X06584Y03039D03*
Y03072D03*
X02139Y03697D03*
Y03664D03*
X02724Y03559D03*
Y03592D03*
X03769Y03234D03*
Y03201D03*
X04454Y03044D03*
Y03077D03*
X04394Y03044D03*
Y03077D03*
X04334Y03044D03*
Y03077D03*
X04274Y03044D03*
Y03077D03*
X04219Y03044D03*
Y03077D03*
X04164Y03044D03*
Y03077D03*
G54D119*
X03269Y02834D03*
Y02814D03*
Y02795D03*
X03209D03*
Y02814D03*
Y02834D03*
G54D120*
X03249Y02784D03*
X03229D03*
Y02845D03*
X03249D03*
G54D121*
X03492Y01398D03*
Y01378D03*
Y01457D03*
Y01477D03*
Y01772D03*
Y01496D03*
Y01792D03*
Y0189D03*
Y01851D03*
Y0187D03*
Y01831D03*
X03651Y0187D03*
Y0189D03*
Y01929D03*
X03492Y01339D03*
Y01359D03*
X03651Y01792D03*
Y01772D03*
Y01851D03*
Y01831D03*
Y01949D03*
Y01988D03*
Y01969D03*
X03492Y01988D03*
Y01969D03*
X03651Y01693D03*
X03492Y01634D03*
Y01673D03*
Y01654D03*
Y01693D03*
X03651Y01733D03*
Y01752D03*
Y01654D03*
Y01575D03*
Y01555D03*
Y01673D03*
Y01634D03*
X03492Y01929D03*
Y01555D03*
Y02008D03*
Y0191D03*
Y01811D03*
Y01713D03*
Y01614D03*
Y01516D03*
Y01418D03*
X03651Y02008D03*
Y0191D03*
Y01811D03*
Y01713D03*
Y01614D03*
Y01516D03*
Y01418D03*
X03492Y01949D03*
X03651Y01595D03*
X03492Y01536D03*
X03651Y01496D03*
Y01477D03*
Y01457D03*
Y01437D03*
Y01398D03*
Y01378D03*
Y01359D03*
Y01339D03*
X03492Y01319D03*
X03651D03*
X03492Y01733D03*
Y01752D03*
X03651Y01536D03*
X03492Y01575D03*
Y01595D03*
Y01437D03*
Y02087D03*
Y02067D03*
Y02047D03*
Y02028D03*
X03651Y02087D03*
Y02067D03*
Y02047D03*
Y02028D03*
X01776Y01634D03*
Y01614D03*
Y0187D03*
Y02028D03*
Y0191D03*
Y01831D03*
Y01949D03*
Y01733D03*
Y01772D03*
X01617Y01929D03*
Y01851D03*
Y0191D03*
Y02028D03*
X01776Y02008D03*
Y01969D03*
Y01457D03*
Y01674D03*
X01617Y0187D03*
Y01969D03*
X01776Y01929D03*
Y01851D03*
Y01811D03*
Y01654D03*
X01617Y02008D03*
X01776Y01752D03*
Y01713D03*
X01617Y01949D03*
X01776Y01555D03*
Y01575D03*
X01617Y01516D03*
Y01457D03*
Y01811D03*
Y01831D03*
X01776Y01437D03*
X01617Y01359D03*
X01776Y01339D03*
X01617Y01575D03*
Y01437D03*
Y01536D03*
Y01555D03*
Y01614D03*
Y01733D03*
Y01674D03*
Y01378D03*
Y01477D03*
Y01418D03*
Y01752D03*
X01776Y01359D03*
X01617Y01339D03*
Y01634D03*
Y01772D03*
X01776Y01378D03*
Y01319D03*
Y01418D03*
X01617Y01319D03*
X01776Y01477D03*
X01617Y01713D03*
Y01654D03*
X01776Y01516D03*
X01617Y02048D03*
X01776D03*
Y01398D03*
Y01496D03*
Y01595D03*
Y01693D03*
Y01792D03*
Y0189D03*
Y01988D03*
X01617Y01398D03*
Y01496D03*
Y01595D03*
Y01693D03*
Y01792D03*
Y0189D03*
Y01988D03*
Y02087D03*
X01776D03*
Y02067D03*
Y01536D03*
X01617Y02067D03*
G54D122*
X03571Y02131D03*
Y01275D03*
X01696Y01275D03*
Y02131D03*
G54D123*
X0298Y02518D03*
Y02358D03*
X02882Y02518D03*
X02783D03*
X02685D03*
X02586D03*
X02488D03*
X0239D03*
X02291D03*
X02882Y02358D03*
X02783D03*
X02685D03*
X02586D03*
X02488D03*
X0239D03*
X02291D03*
X02941D03*
X02961D03*
X02901D03*
X02921D03*
X02842D03*
X02862D03*
X02803D03*
X02823D03*
X02744D03*
X02764D03*
X02705D03*
X02724D03*
X02646D03*
X02665D03*
X02606D03*
X02626D03*
X02547D03*
X02567D03*
X02508D03*
X02527D03*
X02449D03*
X02468D03*
X02409D03*
X02429D03*
X0235D03*
X0237D03*
X02212Y02518D03*
X02232D03*
Y02358D03*
X02212D03*
X02252Y02518D03*
X02272D03*
X02409D03*
X02429D03*
X0235D03*
X0237D03*
X02508D03*
X02527D03*
X02449D03*
X02468D03*
X02606D03*
X02547D03*
X02626D03*
X02567D03*
X02705D03*
X02724D03*
X02646D03*
X02665D03*
X02803D03*
X02823D03*
X02744D03*
X02764D03*
X02901D03*
X02921D03*
X02842D03*
X02862D03*
X02941D03*
X02961D03*
X02252Y02358D03*
X02311D03*
X02331D03*
X02272D03*
X02311Y02518D03*
X02331D03*
X02803Y01038D03*
X02823D03*
X02862Y00878D03*
X02882D03*
X02744D03*
X02764D03*
X02685Y01038D03*
X02705D03*
X02587Y00878D03*
Y01038D03*
X02646Y00878D03*
X02626D03*
X02744Y01038D03*
X02764D03*
X02803Y00878D03*
X02823D03*
X02685D03*
X02705D03*
X02626Y01038D03*
X02646D03*
X02232Y00878D03*
X02429D03*
X0237D03*
X0235D03*
X02331D03*
X02291D03*
X0239D03*
X02488D03*
X02527D03*
X02547D03*
X02567D03*
X02449D03*
X02468D03*
X02252D03*
X02272D03*
X02567Y01038D03*
X0237D03*
X0239D03*
X02429D03*
X02468D03*
X02488D03*
X02449D03*
X02291D03*
X02272D03*
X02252D03*
X02232D03*
X0235D03*
X02331D03*
X02547D03*
X02527D03*
X02862D03*
X02882D03*
X02921Y00878D03*
Y01038D03*
X02941Y00878D03*
Y01038D03*
X0298Y00878D03*
Y01038D03*
X02961D03*
Y00878D03*
X02901Y01038D03*
X02842D03*
X02783D03*
X02724D03*
X02665D03*
X02606D03*
X02508D03*
X02409D03*
X02311D03*
X02901Y00878D03*
X02842D03*
X02783D03*
X02724D03*
X02665D03*
X02606D03*
X02508D03*
X02409D03*
X02311D03*
X02212D03*
Y01038D03*
G54D124*
X02168Y02438D03*
X02168Y00958D03*
X03024D03*
X03024Y02438D03*
G54D125*
X05741Y03361D03*
X05812D03*
X06629Y01421D03*
X067D03*
X06629Y01531D03*
X067D03*
X06439Y03071D03*
X0651D03*
X0373Y00726D03*
X03659D03*
X01802Y04276D03*
X01873D03*
X0428Y03246D03*
X04209D03*
G54D126*
X05634Y03359D03*
X05668D03*
X06327Y02656D03*
X06361D03*
X06327Y02501D03*
X06361D03*
X06327Y02556D03*
X06361D03*
X06327Y02611D03*
X06361D03*
X06676Y01611D03*
X06642D03*
X06676Y01671D03*
X06642D03*
X06676Y01721D03*
X06642D03*
X06676Y01776D03*
X06642D03*
X03716Y00636D03*
X03682D03*
G54D127*
X06906Y02096D03*
X06843D03*
X06093Y02171D03*
X06156D03*
X01664Y04273D03*
X01727D03*
G54D128*
X04275Y03603D03*
X04332D03*
G54D129*
X06749Y02143D03*
Y02088D03*
X06234Y02183D03*
Y02128D03*
X07009Y01883D03*
Y01938D03*
X06004Y02393D03*
Y02338D03*
X02146Y02624D03*
Y02679D03*
X00638Y04038D03*
Y04093D03*
X0084D03*
Y04038D03*
X01042Y04093D03*
Y04038D03*
X01243Y04093D03*
Y04038D03*
X06122Y02488D03*
Y02433D03*
X01933Y04074D03*
Y04129D03*
G54D130*
X02503Y00607D03*
Y00573D03*
X03055Y00607D03*
Y00573D03*
G54D131*
X02334Y03404D03*
Y03483D03*
Y03562D03*
Y0364D03*
X02509Y03404D03*
Y03562D03*
Y03483D03*
Y0364D03*
G54D132*
X01346Y04082D03*
Y04141D03*
Y04037D03*
Y03978D03*
X02151Y04015D03*
Y04074D03*
X02212Y04015D03*
Y04074D03*
X02387Y02899D03*
Y02958D03*
G54D133*
X03958Y04126D03*
X03784D03*
G54D134*
X03294Y04086D03*
X02994D03*
G54D135*
X02422Y03082D03*
Y03239D03*
Y03601D03*
Y03443D03*
G54D136*
X05327Y02307D03*
X05127D03*
X04927D03*
X04727D03*
X04927Y01007D03*
X05127D03*
X04327Y02307D03*
X05327Y01007D03*
G54D137*
X04327Y01007D03*
G54D138*
X05578Y0089D03*
Y01689D03*
Y02489D03*
X03979D03*
Y0089D03*
X04062Y02595D03*
X0418D03*
X04298D03*
G54D139*
X05723Y04025D03*
Y03844D03*
X069Y03806D03*
Y03589D03*
X06734D03*
Y03806D03*
X06569Y03589D03*
Y03806D03*
G54D140*
X05934Y03937D03*
G54D141*
X06119Y04056D03*
G54D142*
X06119Y03819D03*
G54D143*
X00199Y00906D03*
Y02481D03*
Y01956D03*
Y01431D03*
G54D144*
X00299Y01006D03*
Y00806D03*
X00099D03*
Y01006D03*
X00299Y02581D03*
Y02381D03*
X00099D03*
Y02581D03*
X00299Y02056D03*
Y01856D03*
X00099D03*
Y02056D03*
X00299Y01531D03*
Y01331D03*
X00099D03*
Y01531D03*
G54D145*
X03617Y02486D03*
X01652Y00916D03*
X01651Y02486D03*
X03617Y00916D03*
G54D146*
X03571Y02097D03*
Y01309D03*
X02203Y02438D03*
X01696Y01309D03*
Y02097D03*
X02203Y00958D03*
X0299D03*
X0299Y02438D03*
G54D147*
X02043Y04157D03*
Y04057D03*
X01457Y04153D03*
Y04053D03*
G54D148*
X02043Y04257D03*
X01457Y04253D03*
G54D149*
X069Y04093D03*
X06569D03*
G54D150*
X00285Y04152D03*
Y00368D03*
G54D151*
X04039Y03784D03*
X02494Y02661D03*
X02692Y02721D03*
X02511Y00405D03*
X0261Y00279D03*
X02578D03*
X0298Y00409D03*
X02821Y00407D03*
X02748Y00282D03*
X02469Y0041D03*
X02905Y00279D03*
X02878Y00249D03*
X02692Y00795D03*
X02665D03*
X02854Y00405D03*
X02779Y00279D03*
X02665Y00405D03*
X02704D03*
X0235D03*
X02389D03*
X02937Y00279D03*
X02957Y00251D03*
X03019Y00405D03*
X0274Y00976D03*
X02767D03*
X02732Y00795D03*
X02681Y00976D03*
X02708D03*
X02447Y00242D03*
X02413Y00279D03*
X02444D03*
X02606Y00931D03*
X02625Y00795D03*
X02598D03*
X02636Y00247D03*
X02799Y00251D03*
X02826Y00976D03*
X02799D03*
X02649D03*
X02622D03*
X02759Y00795D03*
X02799D03*
X02826D03*
X02862D03*
X02893D03*
X02409Y01088D03*
X02311Y0109D03*
X02508Y00931D03*
X02409Y00932D03*
X02724Y01093D03*
X02784Y01094D03*
X02842Y01095D03*
X02546Y00244D03*
X03097Y00251D03*
X02475Y02291D03*
X0233Y02215D03*
X01798Y01304D03*
X02606Y01091D03*
X03554Y01841D03*
X03719Y01996D03*
X03894Y01566D03*
X03379Y01386D03*
X01721Y0189D03*
X01671Y01792D03*
X01674Y01989D03*
X02508Y0109D03*
X03413Y01573D03*
X0167Y01595D03*
X01754Y02126D03*
X02409Y02579D03*
X02586Y02569D03*
X03197Y01714D03*
X03439Y0187D03*
X03298Y01971D03*
X02985Y02287D03*
X02702Y02289D03*
X02821Y02601D03*
X01718Y01792D03*
X02881Y02566D03*
X03732Y01418D03*
X03554Y01891D03*
X02253Y02279D03*
X02272Y02463D03*
X01719Y01536D03*
X02311Y00934D03*
X03571Y02033D03*
X03554Y01991D03*
X02942Y02286D03*
X02841Y02263D03*
X02394Y0272D03*
X01567Y01285D03*
X01675Y01891D03*
X01568Y02067D03*
X02783Y02429D03*
X03719Y01921D03*
X03773Y01666D03*
X02599Y02436D03*
X02494Y02696D03*
X02894Y02431D03*
X02665Y01092D03*
X02475Y02456D03*
X03414Y01805D03*
X03404Y01363D03*
X02579Y02281D03*
X02685Y02311D03*
X0359Y01662D03*
X02404Y02412D03*
X02803Y02307D03*
X01716Y01399D03*
X01721Y01989D03*
X01619Y02121D03*
X03549Y01413D03*
X02488Y02413D03*
X02726Y02293D03*
X01822Y01674D03*
X0167Y01694D03*
X01884Y02071D03*
X02901Y01095D03*
X0292Y02428D03*
X01893Y01693D03*
X03594Y01514D03*
X0245Y02282D03*
X02409Y02314D03*
X02958Y02621D03*
X03406Y01461D03*
X0341Y01713D03*
X03252Y01661D03*
X02933Y00953D03*
X02871Y02297D03*
X02685Y02568D03*
X03571Y02058D03*
X03804Y0184D03*
X01879Y01811D03*
X03554Y01941D03*
X03392Y01871D03*
X03407Y01411D03*
X02575Y02412D03*
X02499Y02236D03*
X02409Y02283D03*
X02783Y02568D03*
X02948Y02456D03*
X03549Y01441D03*
X03718Y01713D03*
X02624Y02461D03*
X01897Y01516D03*
X03834Y01481D03*
X03864Y01511D03*
X03924Y01536D03*
X03719Y01766D03*
X03329Y01826D03*
X02645Y02274D03*
X02665Y02291D03*
X01721Y01694D03*
X01671Y01399D03*
X02581Y02308D03*
X03803Y01691D03*
X03224Y01661D03*
X02252Y02613D03*
X01718Y01497D03*
X01714Y01595D03*
X01671Y01497D03*
X02321Y02586D03*
X03379Y01336D03*
X01797Y00355D03*
X02034Y00246D03*
X01916Y00244D03*
X02309Y00246D03*
X0333Y03301D03*
X0412Y03594D03*
X01393Y01816D03*
X0099Y00687D03*
X04794Y02808D03*
X03183Y03135D03*
X03277Y02963D03*
X03197Y0297D03*
X03491Y03103D03*
X03188Y03187D03*
X0323Y03235D03*
X03358Y03448D03*
X03068Y03395D03*
X02419Y02788D03*
X02146Y02753D03*
X03275Y03141D03*
X03056Y01811D03*
X02413Y03295D03*
X02254Y03536D03*
X02579Y03486D03*
X02389Y03481D03*
X02321Y03361D03*
X02434Y03546D03*
X02634Y03406D03*
X02631Y02876D03*
X02591Y03186D03*
X0259Y03288D03*
X00996Y02256D03*
X02004Y01336D03*
X02028Y01361D03*
X02549Y01755D03*
X02418Y03118D03*
X02414Y03199D03*
X02462Y03172D03*
X02473Y0298D03*
X02146Y04103D03*
X02253Y04086D03*
X01408Y0398D03*
X01345Y04175D03*
X00996Y01187D03*
X00988Y01717D03*
X00937Y02317D03*
X02353Y04017D03*
X01726Y04329D03*
X01788D03*
X04477Y03135D03*
X04064Y02722D03*
X06628Y01372D03*
X04039Y02406D03*
X06974Y01939D03*
X04134Y01651D03*
X03994Y01551D03*
X04134Y01751D03*
X04151Y01623D03*
X03968Y01671D03*
X03969Y01552D03*
X03944Y01816D03*
X04131Y01686D03*
X04179Y01601D03*
X04034Y01546D03*
X03996Y01711D03*
X04064Y01796D03*
Y01511D03*
X03263Y03303D03*
X0396Y02724D03*
X01569Y04171D03*
X02076Y00255D03*
Y00287D03*
X02112D03*
X02151D03*
X02112Y00255D03*
X02151D03*
X01832D03*
X01852D03*
X01872D03*
X01832Y00287D03*
X01852D03*
X01872D03*
X06253Y02909D03*
X06647Y03129D03*
X05267Y04088D03*
X04339Y02725D03*
X04503Y02789D03*
X02231Y02584D03*
X05994Y03552D03*
X04049Y03665D03*
X03829Y03806D03*
X05577Y02214D03*
X02694Y01481D03*
X02384Y01941D03*
X0383Y03762D03*
X06334Y03266D03*
X03744Y03261D03*
X03395Y04222D03*
X04272Y03135D03*
X05634Y02236D03*
X02626Y0177D03*
X06304Y03121D03*
X03939D03*
X02139Y03738D03*
X04208Y03135D03*
X02604Y01734D03*
X06626Y03032D03*
X04152Y03135D03*
X02299Y01916D03*
X02724Y03521D03*
X01248Y02D03*
X02579Y0179D03*
X04068Y03135D03*
X02674Y03501D03*
X04234Y02725D03*
X06456Y03009D03*
X01691Y04079D03*
X03642Y00636D03*
X02259Y03261D03*
X03374Y03273D03*
X03368Y0305D03*
X06476Y03231D03*
X04333Y03135D03*
X01557Y04229D03*
X06282Y03226D03*
X03806Y03235D03*
X01261Y02482D03*
X04114Y03135D03*
X06648Y03341D03*
X02888Y04221D03*
X0337Y02888D03*
X02258Y03741D03*
X01749Y0411D03*
X0257Y04283D03*
X01459Y03147D03*
X0144Y03557D03*
X01903Y04018D03*
X0229Y04217D03*
X0388Y03109D03*
X03623Y02587D03*
X03622Y03486D03*
X03491Y03297D03*
X03542Y03319D03*
X03344Y02996D03*
X03744Y03342D03*
X03653Y03293D03*
X03394Y03447D03*
X03436Y03457D03*
X03717Y03072D03*
X02799Y03616D03*
X03589Y01711D03*
X05733Y03556D03*
X05676Y03546D03*
X03603Y00682D03*
X02478Y00937D03*
X06548Y01531D03*
X06602Y01612D03*
Y01672D03*
Y01722D03*
X06601Y01777D03*
X06685Y01828D03*
X06699Y01881D03*
X06949Y02095D03*
X06607Y02176D03*
X06395Y02111D03*
X06048Y02171D03*
X06004Y02434D03*
X06274Y02391D03*
X06398Y02453D03*
X06397Y02501D03*
X06396Y02556D03*
X06397Y0261D03*
X06398Y02657D03*
X06372Y02909D03*
X0491Y04203D03*
X04387Y04206D03*
X03777Y04023D03*
X04085Y03892D03*
X04194Y03884D03*
X04431Y03135D03*
X0286Y03787D03*
X02724Y03729D03*
X03531Y0366D03*
X03269Y03788D03*
X01242Y01472D03*
X01256Y00942D03*
X00654Y0079D03*
X00655Y01028D03*
X00654Y01314D03*
X00653Y01551D03*
X00654Y01839D03*
Y02073D03*
Y02365D03*
X00653Y02593D03*
X02206Y01298D03*
X02205Y032D03*
X02502Y01316D03*
X02525Y02463D03*
X03342Y02263D03*
X03498Y02341D03*
X02429Y02621D03*
X01004Y00906D03*
X02446Y01437D03*
X01008Y0143D03*
X02409Y01967D03*
X01009Y01956D03*
X0102Y02481D03*
X02643Y01616D03*
X02666Y0164D03*
X01884Y03601D03*
X01754Y03661D03*
X03424Y03636D03*
X01549Y03621D03*
X03239Y03596D03*
X01574D03*
X03539Y03806D03*
X03219D03*
X02722Y03786D03*
X02139Y03611D03*
X02084Y03896D03*
X02083Y01411D03*
X02059Y01386D03*
Y03871D03*
X02029Y03836D03*
X01294Y04256D03*
X02004Y03816D03*
X02234Y03506D03*
X03529Y03481D03*
X05274Y03511D03*
X06284Y02501D03*
X02679Y03661D03*
X02774Y03566D03*
X02993Y03751D03*
X03699D03*
X03014Y03831D03*
X03699Y03836D03*
X04254Y03776D03*
X02894Y01561D03*
X02919Y01536D03*
X02274Y01506D03*
X02719Y01591D03*
X03724Y01675D03*
X06844Y01661D03*
X06424Y02181D03*
X06309Y03199D03*
X06339Y03151D03*
X04754Y04115D03*
X01779Y04156D03*
X03504Y04086D03*
X03854Y03151D03*
X03829Y03176D03*
X03799Y03201D03*
X06439Y03191D03*
X06354Y03331D03*
X06444Y03291D03*
X03302Y03344D03*
X06409Y03371D03*
X06447Y03396D03*
X06479Y03426D03*
X06509Y03456D03*
X03469D03*
X01849Y03701D03*
X06294D03*
G54D152*
X02531Y03853D03*
Y0283D03*
X00149D03*
Y03853D03*
M02*